# T6G (Grand Teton) — schematic netlist excerpt (pin names and nets, part order shuffled) for the footprints in the layout excerpt that follows; sources: Cadence DE-HDL packaged netlist, KiCad conversion of 04192023_DAF0TMB3IC0_F0TG_MB_C_brd_V02_OCP.brd

PL11  Q_INDUCTOR4P_14  150NH IND  pkg L_TLM117513Q-151QL_11X7-5XA  page 201
  \1\  = SW_PVDDCR_CPU1_P0_SW2
  \2\  = IND_CPU1_P0_CPL1
  \3\  = IND_CPU1_P0_CPL2
  \4\  = PVDDCR_CPU1_P0

R3396  Q_RES  2.2K 5% CHIP  pkg 0402LF  page 250 : A = P3V3_AUX ; B = SMB_INA230_3V3AUX_SDA
C897  Q_CAP_DIFFBUS  DIFF BUS_0.22UF 6.3V 20% X6S  pkg C0201  page 64 : \1\ = P5E_CPU0_P3_TX_C_DP<2> ; \2\ = P5E_CPU0_P3_TX_DP<2>

(kicad_pcb
	(version 20260206)
	(generator "pcbnew")
	(generator_version "10.0")
	(general
		(thickness 1.6)
		(legacy_teardrops no)
	)
	(paper "A4")
	(title_block
		(title "04192023_DAF0TMB3IC0_F0TG_MB_C_brd_V02_OCP.brd")
		(comment 1 "Grand Teton / footprints 3436-3438 of 8354")
	)
	(layers
		(0 "F.Cu" signal "TOP")
		(4 "In1.Cu" signal "GND")
		(6 "In2.Cu" signal "IN1")
		(8 "In3.Cu" signal "GND1")
		(10 "In4.Cu" signal "IN2")
		(12 "In5.Cu" signal "GND2")
		(14 "In6.Cu" signal "IN3")
		(16 "In7.Cu" signal "GND3")
		(18 "In8.Cu" signal "VCC")
		(20 "In9.Cu" signal "VCC1")
		(22 "In10.Cu" signal "GND4")
		(24 "In11.Cu" signal "IN4")
		(26 "In12.Cu" signal "GND5")
		(28 "In13.Cu" signal "IN5")
		(30 "In14.Cu" signal "GND6")
		(32 "In15.Cu" signal "IN6")
		(34 "In16.Cu" signal "GND7")
		(2 "B.Cu" signal "BOTTOM")
		(9 "F.Adhes" user "F.Adhesive")
		(11 "B.Adhes" user "B.Adhesive")
		(13 "F.Paste" user "Package Geometry/Pastemask Top")
		(15 "B.Paste" user "Package Geometry/Pastemask Bottom")
		(5 "F.SilkS" user "Ref Des/Silkscreen Top")
		(7 "B.SilkS" user "Ref Des/Silkscreen Bottom")
		(1 "F.Mask" user "Board Geometry/Soldermask Top")
		(3 "B.Mask" user "Board Geometry/Soldermask Bottom")
		(17 "Dwgs.User" user "User.Drawings")
		(19 "Cmts.User" user "User.Comments")
		(21 "Eco1.User" user "User.Eco1")
		(23 "Eco2.User" user "User.Eco2")
		(25 "Edge.Cuts" user "Board Geometry/Outline")
		(27 "Margin" user)
		(31 "F.CrtYd" user "Package Geometry/Place Bound Top")
		(29 "B.CrtYd" user "Package Geometry/Place Bound Bottom")
		(35 "F.Fab" user "Ref Des/Assembly Top")
		(33 "B.Fab" user "Ref Des/Assembly Bottom")
	)
	(footprint ""
		(layer "F.Cu")
		(at 297.486324 -117.942614 180)
		(property "Reference" "R3396"
			(at 0 0 180)
			(layer "F.SilkS")
			(hide yes)
			(effects
				(font
					(size 1.27 1.27)
				)
			)
		)
		(property "Value" ""
			(at 0 0 180)
			(layer "F.Fab")
			(effects
				(font
					(size 1.27 1.27)
				)
			)
		)
		(duplicate_pad_numbers_are_jumpers no)
		(fp_line
			(start 0.7874 0.4064)
			(end -0.7874 0.4064)
			(stroke
				(width 0.1524)
				(type default)
			)
			(layer "F.SilkS")
		)
		(fp_line
			(start 0.7874 -0.4064)
			(end 0.7874 0.4064)
			(stroke
				(width 0.1524)
				(type default)
			)
			(layer "F.SilkS")
		)
		(fp_line
			(start -0.7874 0.4064)
			(end -0.7874 -0.4064)
			(stroke
				(width 0.1524)
				(type default)
			)
			(layer "F.SilkS")
		)
		(fp_line
			(start -0.7874 -0.4064)
			(end 0.7874 -0.4064)
			(stroke
				(width 0.1524)
				(type default)
			)
			(layer "F.SilkS")
		)
		(fp_line
			(start 0.67945 0.3048)
			(end 0.120396 0.3048)
			(stroke
				(width 0.1)
				(type default)
			)
			(layer "F.Fab")
		)
		(fp_line
			(start 0.67945 -0.3048)
			(end 0.67945 0.3048)
			(stroke
				(width 0.1)
				(type default)
			)
			(layer "F.Fab")
		)
		(fp_line
			(start 0.12065 -0.2794)
			(end 0.12065 -0.3048)
			(stroke
				(width 0.1)
				(type default)
			)
			(layer "F.Fab")
		)
		(fp_line
			(start 0.12065 -0.3048)
			(end 0.67945 -0.3048)
			(stroke
				(width 0.1)
				(type default)
			)
			(layer "F.Fab")
		)
		(fp_line
			(start 0.120396 0.3048)
			(end 0.120396 0.2794)
			(stroke
				(width 0.1)
				(type default)
			)
			(layer "F.Fab")
		)
		(fp_line
			(start 0.120396 0.2794)
			(end -0.12065 0.2794)
			(stroke
				(width 0.1)
				(type default)
			)
			(layer "F.Fab")
		)
		(fp_line
			(start -0.12065 0.3048)
			(end -0.67945 0.3048)
			(stroke
				(width 0.1)
				(type default)
			)
			(layer "F.Fab")
		)
		(fp_line
			(start -0.12065 0.2794)
			(end -0.12065 0.3048)
			(stroke
				(width 0.1)
				(type default)
			)
			(layer "F.Fab")
		)
		(fp_line
			(start -0.12065 -0.2794)
			(end 0.12065 -0.2794)
			(stroke
				(width 0.1)
				(type default)
			)
			(layer "F.Fab")
		)
		(fp_line
			(start -0.12065 -0.305054)
			(end -0.12065 -0.2794)
			(stroke
				(width 0.1)
				(type default)
			)
			(layer "F.Fab")
		)
		(fp_line
			(start -0.67945 0.3048)
			(end -0.67945 -0.305054)
			(stroke
				(width 0.1)
				(type default)
			)
			(layer "F.Fab")
		)
		(fp_line
			(start -0.67945 -0.305054)
			(end -0.12065 -0.305054)
			(stroke
				(width 0.1)
				(type default)
			)
			(layer "F.Fab")
		)
		(pad "1" smd circle
			(at -0.40005 0 180)
			(size 0 0)
			(layers "F.Cu" "F.Mask" "F.Paste")
			(net "P3V3_AUX")
		)
		(pad "2" smd circle
			(at 0.40005 0 180)
			(size 0 0)
			(layers "F.Cu" "F.Mask" "F.Paste")
			(net "SMB_INA230_3V3AUX_SDA")
		)
	)
	(footprint ""
		(layer "F.Cu")
		(at 366.089692 -381.41783 -90)
		(property "Reference" "C897"
			(at 0 0 270)
			(layer "F.SilkS")
			(hide yes)
			(effects
				(font
					(size 1.27 1.27)
				)
			)
		)
		(property "Value" ""
			(at 0 0 270)
			(layer "F.Fab")
			(effects
				(font
					(size 1.27 1.27)
				)
			)
		)
		(duplicate_pad_numbers_are_jumpers no)
		(fp_line
			(start -0.299974 0.150114)
			(end -0.299974 -0.150114)
			(stroke
				(width 0.1)
				(type default)
			)
			(layer "F.Fab")
		)
		(fp_line
			(start 0.299974 0.150114)
			(end -0.299974 0.150114)
			(stroke
				(width 0.1)
				(type default)
			)
			(layer "F.Fab")
		)
		(fp_line
			(start -0.299974 -0.150114)
			(end 0.299974 -0.150114)
			(stroke
				(width 0.1)
				(type default)
			)
			(layer "F.Fab")
		)
		(fp_line
			(start 0.299974 -0.150114)
			(end 0.299974 0.150114)
			(stroke
				(width 0.1)
				(type default)
			)
			(layer "F.Fab")
		)
		(pad "1" smd rect
			(at -0.2667 0 270)
			(size 0.3048 0.381)
			(layers "F.Cu" "F.Mask" "F.Paste")
			(net "P5E_CPU0_P3_TX_C_DP<2>")
		)
		(pad "2" smd rect
			(at 0.2667 0 270)
			(size 0.3048 0.381)
			(layers "F.Cu" "F.Mask" "F.Paste")
			(net "P5E_CPU0_P3_TX_DP<2>")
		)
	)
	(footprint ""
		(layer "F.Cu")
		(at 326.81926 -325.656448)
		(property "Reference" "PL11"
			(at 0.313944 -15.887446 0)
			(unlocked yes)
			(layer "F.SilkS")
			(effects
				(font
					(size 0.7874 0.5842)
					(thickness 0.1524)
				)
				(justify left)
			)
		)
		(property "Value" ""
			(at 0 0 0)
			(layer "F.Fab")
			(effects
				(font
					(size 1.27 1.27)
				)
			)
		)
		(duplicate_pad_numbers_are_jumpers no)
		(fp_line
			(start -3.750056 -5.500116)
			(end -2.393442 -5.500116)
			(stroke
				(width 0.1524)
				(type default)
			)
			(layer "F.SilkS")
		)
		(fp_line
			(start -3.750056 5.500116)
			(end -3.750056 -5.500116)
			(stroke
				(width 0.1524)
				(type default)
			)
			(layer "F.SilkS")
		)
		(fp_line
			(start -2.393442 5.500116)
			(end -3.750056 5.500116)
			(stroke
				(width 0.1524)
				(type default)
			)
			(layer "F.SilkS")
		)
		(fp_line
			(start 2.393442 5.500116)
			(end 3.750056 5.500116)
			(stroke
				(width 0.1524)
				(type default)
			)
			(layer "F.SilkS")
		)
		(fp_line
			(start 3.750056 -5.500116)
			(end 2.393442 -5.500116)
			(stroke
				(width 0.1524)
				(type default)
			)
			(layer "F.SilkS")
		)
		(fp_line
			(start 3.750056 5.500116)
			(end 3.750056 -5.500116)
			(stroke
				(width 0.1524)
				(type default)
			)
			(layer "F.SilkS")
		)
		(fp_poly
			(pts
				(xy -3.9116 -4.249928) (xy -4.3434 -4.034028) (xy -4.3434 -4.465828)
			)
			(stroke
				(width 0)
				(type default)
			)
			(fill yes)
			(layer "F.SilkS")
		)
		(fp_line
			(start -3.750056 -5.500116)
			(end -3.750056 5.500116)
			(stroke
				(width 0.1)
				(type default)
			)
			(layer "F.Fab")
		)
		(fp_line
			(start -3.750056 5.500116)
			(end 3.750056 5.500116)
			(stroke
				(width 0.1)
				(type default)
			)
			(layer "F.Fab")
		)
		(fp_line
			(start 3.750056 -5.500116)
			(end -3.750056 -5.500116)
			(stroke
				(width 0.1)
				(type default)
			)
			(layer "F.Fab")
		)
		(fp_line
			(start 3.750056 5.500116)
			(end 3.750056 -5.500116)
			(stroke
				(width 0.1)
				(type default)
			)
			(layer "F.Fab")
		)
		(fp_poly
			(pts
				(xy -4.9276 -4.757928) (xy -4.9276 -3.741928) (xy -3.9116 -4.249928)
			)
			(stroke
				(width 0)
				(type default)
			)
			(fill yes)
			(layer "F.Fab")
		)
		(pad "1" smd rect
			(at 0 -4.249928 270)
			(size 2.413 4.5212)
			(layers "F.Cu" "F.Mask" "F.Paste")
			(net "SW_PVDDCR_CPU1_P0_SW2")
		)
		(pad "2" smd rect
			(at 0 -1.175004 270)
			(size 1.3716 4.5212)
			(layers "F.Cu" "F.Mask" "F.Paste")
			(net "IND_CPU1_P0_CPL1")
		)
		(pad "3" smd rect
			(at 0 1.175004 270)
			(size 1.3716 4.5212)
			(layers "F.Cu" "F.Mask" "F.Paste")
			(net "IND_CPU1_P0_CPL2")
		)
		(pad "4" smd rect
			(at 0 4.249928 270)
			(size 2.413 4.5212)
			(layers "F.Cu" "F.Mask" "F.Paste")
			(net "PVDDCR_CPU1_P0")
		)
	)
)
